(kicad_pcb
	(version 20241229)
	(generator "pcbnew")
	(generator_version "9.0")
	(general
		(thickness 1.62)
		(legacy_teardrops no)
	)
	(paper "A4")
	(title_block
		(title "OCuLink to 10GbE adapter")
		(date "2026-02-23")
		(rev "1.1.0")
		(company "Antmicro Ltd")
		(comment 1 "www.antmicro.com")
		(comment 9 "footprints 322-326 of 510")
	)
	(layers
		(0 "F.Cu" signal)
		(4 "In1.Cu" signal)
		(6 "In2.Cu" signal)
		(8 "In3.Cu" signal)
		(10 "In4.Cu" signal)
		(12 "In5.Cu" signal)
		(14 "In6.Cu" signal)
		(2 "B.Cu" signal)
		(9 "F.Adhes" user "F.Adhesive")
		(11 "B.Adhes" user "B.Adhesive")
		(13 "F.Paste" user)
		(15 "B.Paste" user)
		(5 "F.SilkS" user "F.Silkscreen")
		(7 "B.SilkS" user "B.Silkscreen")
		(1 "F.Mask" user)
		(3 "B.Mask" user)
		(17 "Dwgs.User" user "User.Drawings")
		(19 "Cmts.User" user "User.Comments")
		(21 "Eco1.User" user "User.Eco1")
		(23 "Eco2.User" user "User.Eco2")
		(25 "Edge.Cuts" user)
		(27 "Margin" user)
		(31 "F.CrtYd" user "F.Courtyard")
		(29 "B.CrtYd" user "B.Courtyard")
		(35 "F.Fab" user)
		(33 "B.Fab" user)
	)
	(footprint "antmicro-footprints:USON-10_2.5x1mm_P0.5mm"
		(layer "B.Cu")
		(at 99.75 55.88366 90)
		(descr "USON-10 2.5x1mm_ Pitch 0.5mm")
		(tags "USON-10 2.5x1mm Pitch 0.5mm")
		(property "Reference" "D9"
			(at -0.90134 -0.75 180)
			(layer "B.SilkS")
			(effects
				(font
					(size 0.7 0.7)
					(thickness 0.15)
				)
				(justify right top mirror)
			)
		)
		(property "Value" "ESD204DQAR"
			(at 0.018 -2.499 90)
			(layer "B.Fab")
			(hide yes)
			(effects
				(font
					(size 0.7 0.7)
					(thickness 0.15)
				)
				(justify right top mirror)
			)
		)
		(property "Datasheet" "https://www.ti.com/lit/ds/symlink/esd204.pdf?ts=1706004844383&ref_url=https%253A%252F%252Fwww.ti.com%252Finterface%252Fdiodes%252Fesd-protection-diodes%252Fproducts.html"
			(at 0 0 90)
			(layer "B.Fab")
			(hide yes)
			(effects
				(font
					(size 1.27 1.27)
					(thickness 0.15)
				)
				(justify mirror)
			)
		)
		(property "Description" "TVS diode array, 30 kV, USON-10, 3.6 V, 0.55 pF"
			(at 0 0 90)
			(layer "B.Fab")
			(hide yes)
			(effects
				(font
					(size 1.27 1.27)
					(thickness 0.15)
				)
				(justify mirror)
			)
		)
		(property "MPN" "ESD204DQAR"
			(at 0 0 90)
			(unlocked yes)
			(layer "B.Fab")
			(hide yes)
			(effects
				(font
					(size 1 1)
					(thickness 0.15)
				)
				(justify mirror)
			)
		)
		(property "Manufacturer" "Texas Instruments"
			(at 0 0 90)
			(unlocked yes)
			(layer "B.Fab")
			(hide yes)
			(effects
				(font
					(size 1 1)
					(thickness 0.15)
				)
				(justify mirror)
			)
		)
		(property "Author" "Antmicro"
			(at 0 0 90)
			(unlocked yes)
			(layer "B.Fab")
			(hide yes)
			(effects
				(font
					(size 1 1)
					(thickness 0.15)
				)
				(justify mirror)
			)
		)
		(property "License" "Apache-2.0"
			(at 0 0 90)
			(unlocked yes)
			(layer "B.Fab")
			(hide yes)
			(effects
				(font
					(size 1 1)
					(thickness 0.15)
				)
				(justify mirror)
			)
		)
		(sheetname "/OCuLink/")
		(sheetfile "oculink.kicad_sch")
		(attr smd)
		(fp_line
			(start 0.498 -1.398)
			(end -0.5 -1.398)
			(stroke
				(width 0.15)
				(type solid)
			)
			(layer "B.SilkS")
		)
		(fp_line
			(start 0.498 1.401)
			(end -0.5 1.401)
			(stroke
				(width 0.15)
				(type solid)
			)
			(layer "B.SilkS")
		)
		(fp_circle
			(center -0.68 1.27)
			(end -0.63 1.27)
			(stroke
				(width 0.15)
				(type solid)
			)
			(fill yes)
			(layer "B.SilkS")
		)
		(fp_rect
			(start -0.8 1.5)
			(end 0.8 -1.499)
			(stroke
				(width 0.05)
				(type solid)
			)
			(fill no)
			(layer "B.CrtYd")
		)
		(fp_line
			(start -0.5 -1.249)
			(end 0.498 -1.249)
			(stroke
				(width 0.15)
				(type solid)
			)
			(layer "B.Fab")
		)
		(fp_line
			(start -0.5 1)
			(end -0.5 -1.249)
			(stroke
				(width 0.15)
				(type solid)
			)
			(layer "B.Fab")
		)
		(fp_line
			(start 0.498 1.25)
			(end 0.498 -1.249)
			(stroke
				(width 0.15)
				(type solid)
			)
			(layer "B.Fab")
		)
		(fp_line
			(start 0.498 1.25)
			(end -0.25 1.25)
			(stroke
				(width 0.15)
				(type solid)
			)
			(layer "B.Fab")
		)
		(fp_line
			(start -0.25 1.25)
			(end -0.5 1)
			(stroke
				(width 0.15)
				(type solid)
			)
			(layer "B.Fab")
		)
		(pad "1" smd roundrect
			(at -0.387 1 180)
			(size 0.25 0.55)
			(layers "B.Cu" "B.Mask" "B.Paste")
			(roundrect_rratio 0.25)
			(net 304 "/OCuLink/SCL")
			(pintype "passive")
		)
		(pad "2" smd roundrect
			(at -0.387 0.5 180)
			(size 0.25 0.55)
			(layers "B.Cu" "B.Mask" "B.Paste")
			(roundrect_rratio 0.25)
			(net 226 "/OCuLink/SDA")
			(pintype "passive")
		)
		(pad "3" smd roundrect
			(at -0.387 0 180)
			(size 0.4 0.55)
			(layers "B.Cu" "B.Mask" "B.Paste")
			(roundrect_rratio 0.25)
			(net 28 "GND")
			(pintype "power_in")
		)
		(pad "4" smd roundrect
			(at -0.387 -0.498 180)
			(size 0.25 0.55)
			(layers "B.Cu" "B.Mask" "B.Paste")
			(roundrect_rratio 0.25)
			(net 319 "/OCuLink/~{PE_ RST}_R")
			(pintype "passive")
		)
		(pad "5" smd roundrect
			(at -0.387 -0.998 180)
			(size 0.25 0.55)
			(layers "B.Cu" "B.Mask" "B.Paste")
			(roundrect_rratio 0.25)
			(net 321 "/OCuLink/~{CPRSNT}_R")
			(pintype "passive")
		)
		(pad "6" smd roundrect
			(at 0.385 -0.998 180)
			(size 0.25 0.55)
			(layers "B.Cu" "B.Mask" "B.Paste")
			(roundrect_rratio 0.25)
			(net 321 "/OCuLink/~{CPRSNT}_R")
			(pintype "passive")
		)
		(pad "7" smd roundrect
			(at 0.385 -0.498 180)
			(size 0.25 0.55)
			(layers "B.Cu" "B.Mask" "B.Paste")
			(roundrect_rratio 0.25)
			(net 319 "/OCuLink/~{PE_ RST}_R")
			(pintype "passive")
		)
		(pad "8" smd roundrect
			(at 0.385 0 180)
			(size 0.4 0.55)
			(layers "B.Cu" "B.Mask" "B.Paste")
			(roundrect_rratio 0.25)
			(net 28 "GND")
			(pintype "passive")
		)
		(pad "9" smd roundrect
			(at 0.385 0.5 180)
			(size 0.25 0.55)
			(layers "B.Cu" "B.Mask" "B.Paste")
			(roundrect_rratio 0.25)
			(net 226 "/OCuLink/SDA")
			(pintype "passive")
		)
		(pad "10" smd roundrect
			(at 0.385 1 180)
			(size 0.25 0.55)
			(layers "B.Cu" "B.Mask" "B.Paste")
			(roundrect_rratio 0.25)
			(net 304 "/OCuLink/SCL")
			(pintype "passive")
		)
	)
	(footprint "antmicro-footprints:SOT-416"
		(layer "B.Cu")
		(at 56.25 125.1)
		(descr "SOT-416")
		(tags "SOT-416")
		(property "Reference" "Q5"
			(at 1.169999 0.8 90)
			(layer "B.SilkS")
			(effects
				(font
					(size 0.7 0.7)
					(thickness 0.15)
				)
				(justify right top mirror)
			)
		)
		(property "Value" "DTC014T_SOT-416"
			(at 0 -2.000001 0)
			(layer "B.Fab")
			(hide yes)
			(effects
				(font
					(size 0.7 0.7)
					(thickness 0.15)
				)
				(justify right top mirror)
			)
		)
		(property "Datasheet" "https://www.rohm.com/datasheet?p=DTC014TEB&dist=Mouser&media=referral&source=mouser.com&campaign=Mouser"
			(at 0 0 0)
			(layer "B.Fab")
			(hide yes)
			(effects
				(font
					(size 1.27 1.27)
					(thickness 0.15)
				)
				(justify mirror)
			)
		)
		(property "Description" "Bipolar (BJT) Single Transistor with built-in base resistor, NPN, 50V, 100mA, 150mW, SOT-416FL, Surface Mount"
			(at 0 0 0)
			(layer "B.Fab")
			(hide yes)
			(effects
				(font
					(size 1.27 1.27)
					(thickness 0.15)
				)
				(justify mirror)
			)
		)
		(property "Manufacturer" "ROHM Semiconductor"
			(at 0 0 180)
			(unlocked yes)
			(layer "B.Fab")
			(hide yes)
			(effects
				(font
					(size 1 1)
					(thickness 0.15)
				)
				(justify mirror)
			)
		)
		(property "MPN" "DTC014TEBTL"
			(at 0 0 180)
			(unlocked yes)
			(layer "B.Fab")
			(hide yes)
			(effects
				(font
					(size 1 1)
					(thickness 0.15)
				)
				(justify mirror)
			)
		)
		(property "Author" "Antmicro"
			(at 0 0 180)
			(unlocked yes)
			(layer "B.Fab")
			(hide yes)
			(effects
				(font
					(size 1 1)
					(thickness 0.15)
				)
				(justify mirror)
			)
		)
		(property "License" "Apache-2.0"
			(at 0 0 180)
			(unlocked yes)
			(layer "B.Fab")
			(hide yes)
			(effects
				(font
					(size 1 1)
					(thickness 0.15)
				)
				(justify mirror)
			)
		)
		(sheetname "/Power/")
		(sheetfile "power.kicad_sch")
		(attr smd)
		(fp_line
			(start -0.5 0.15)
			(end -0.5 -0.15)
			(stroke
				(width 0.15)
				(type solid)
			)
			(layer "B.SilkS")
		)
		(fp_line
			(start 0.5 -0.9)
			(end -0.5 -0.9)
			(stroke
				(width 0.15)
				(type solid)
			)
			(layer "B.SilkS")
		)
		(fp_line
			(start 0.5 -0.9)
			(end 0.5 -0.7)
			(stroke
				(width 0.15)
				(type solid)
			)
			(layer "B.SilkS")
		)
		(fp_line
			(start 0.508 0.9)
			(end -0.5 0.9)
			(stroke
				(width 0.15)
				(type solid)
			)
			(layer "B.SilkS")
		)
		(fp_line
			(start 0.508 0.9)
			(end 0.508 0.592)
			(stroke
				(width 0.15)
				(type solid)
			)
			(layer "B.SilkS")
		)
		(fp_rect
			(start -1 1.05)
			(end 1 -1.05)
			(stroke
				(width 0.05)
				(type solid)
			)
			(fill no)
			(layer "B.CrtYd")
		)
		(fp_line
			(start -0.05 0.9)
			(end -0.45 0.5)
			(stroke
				(width 0.15)
				(type solid)
			)
			(layer "B.Fab")
		)
		(fp_rect
			(start 0.45 -0.9)
			(end -0.45 0.9)
			(stroke
				(width 0.15)
				(type solid)
			)
			(fill no)
			(layer "B.Fab")
		)
		(fp_text user "${REFERENCE}"
			(at -1 -3.4 180)
			(layer "B.Fab")
			(effects
				(font
					(size 0.7 0.7)
					(thickness 0.15)
				)
				(justify left bottom mirror)
			)
		)
		(fp_text user "Author: Antmicro"
			(at -1 -4.602 180)
			(layer "B.Fab")
			(effects
				(font
					(size 0.7 0.7)
					(thickness 0.15)
				)
				(justify left bottom mirror)
			)
		)
		(fp_text user "License: Apache-2.0"
			(at -1 -5.802 180)
			(layer "B.Fab")
			(effects
				(font
					(size 0.7 0.7)
					(thickness 0.15)
				)
				(justify left bottom mirror)
			)
		)
		(pad "1" smd rect
			(at -0.652 0.5)
			(size 0.6 0.5)
			(layers "B.Cu" "B.Mask" "B.Paste")
			(net 303 "/Power/+VCCD_OUT")
			(pinfunction "B")
			(pintype "input")
		)
		(pad "2" smd rect
			(at -0.652 -0.498)
			(size 0.6 0.5)
			(layers "B.Cu" "B.Mask" "B.Paste")
			(net 28 "GND")
			(pinfunction "E")
			(pintype "passive")
		)
		(pad "3" smd rect
			(at 0.65 0)
			(size 0.6 0.5)
			(layers "B.Cu" "B.Mask" "B.Paste")
			(net 416 "Net-(Q5-C)")
			(pinfunction "C")
			(pintype "passive")
		)
	)
	(footprint "antmicro-footprints:C_0402_1005Metric"
		(layer "B.Cu")
		(at 93.48 145.34 -90)
		(descr "Capacitor SMD 0402")
		(tags "capacitor SMD 0402")
		(property "Reference" "C62"
			(at -2.91 -0.47 90)
			(layer "B.SilkS")
			(effects
				(font
					(size 0.7 0.7)
					(thickness 0.15)
				)
				(justify left bottom mirror)
			)
		)
		(property "Value" "C_470p_0402"
			(at -1.022927 -2.155213 90)
			(layer "B.Fab")
			(hide yes)
			(effects
				(font
					(size 0.7 0.7)
					(thickness 0.15)
				)
				(justify left bottom mirror)
			)
		)
		(property "Datasheet" "https://www.passivecomponent.com/wp-content/uploads/datasheet/WTC_MLCC_General_Purpose.pdf"
			(at 0 0 90)
			(layer "B.Fab")
			(hide yes)
			(effects
				(font
					(size 1.27 1.27)
					(thickness 0.15)
				)
				(justify mirror)
			)
		)
		(property "Description" "SMD Multilayer Ceramic Capacitor, General Purpose, 470 pF, 25 V, 0402 [1005 Metric], ± 10%, X7R"
			(at 0 0 90)
			(layer "B.Fab")
			(hide yes)
			(effects
				(font
					(size 1.27 1.27)
					(thickness 0.15)
				)
				(justify mirror)
			)
		)
		(property "MPN" "0402B471K250CT"
			(at 0 0 270)
			(unlocked yes)
			(layer "B.Fab")
			(hide yes)
			(effects
				(font
					(size 1 1)
					(thickness 0.15)
				)
				(justify mirror)
			)
		)
		(property "Manufacturer" "Walsin"
			(at 0 0 270)
			(unlocked yes)
			(layer "B.Fab")
			(hide yes)
			(effects
				(font
					(size 1 1)
					(thickness 0.15)
				)
				(justify mirror)
			)
		)
		(property "License" "Apache-2.0"
			(at 0 0 270)
			(unlocked yes)
			(layer "B.Fab")
			(hide yes)
			(effects
				(font
					(size 1 1)
					(thickness 0.15)
				)
				(justify mirror)
			)
		)
		(property "Author" "Antmicro"
			(at 0 0 270)
			(unlocked yes)
			(layer "B.Fab")
			(hide yes)
			(effects
				(font
					(size 1 1)
					(thickness 0.15)
				)
				(justify mirror)
			)
		)
		(property "Val" "470p"
			(at 0 0 270)
			(unlocked yes)
			(layer "B.Fab")
			(hide yes)
			(effects
				(font
					(size 1 1)
					(thickness 0.15)
				)
				(justify mirror)
			)
		)
		(property "Voltage" "25V"
			(at 0 0 270)
			(unlocked yes)
			(layer "B.Fab")
			(hide yes)
			(effects
				(font
					(size 1 1)
					(thickness 0.15)
				)
				(justify mirror)
			)
		)
		(property "Dielectric" "X7R"
			(at 0 0 270)
			(unlocked yes)
			(layer "B.Fab")
			(hide yes)
			(effects
				(font
					(size 1 1)
					(thickness 0.15)
				)
				(justify mirror)
			)
		)
		(sheetname "/2xRJ45/")
		(sheetfile "2xrj45.kicad_sch")
		(attr smd)
		(fp_rect
			(start -0.925 0.47)
			(end 0.925 -0.47)
			(stroke
				(width 0.05)
				(type default)
			)
			(fill no)
			(layer "B.CrtYd")
		)
		(fp_line
			(start -0.494 0.25)
			(end 0.504 0.25)
			(stroke
				(width 0.15)
				(type solid)
			)
			(layer "B.Fab")
		)
		(fp_line
			(start 0.504 0.25)
			(end 0.504 -0.248)
			(stroke
				(width 0.15)
				(type solid)
			)
			(layer "B.Fab")
		)
		(fp_line
			(start -0.494 -0.248)
			(end -0.494 0.25)
			(stroke
				(width 0.15)
				(type solid)
			)
			(layer "B.Fab")
		)
		(fp_line
			(start 0.504 -0.248)
			(end -0.494 -0.248)
			(stroke
				(width 0.15)
				(type solid)
			)
			(layer "B.Fab")
		)
		(pad "1" smd roundrect
			(at -0.48 0 270)
			(size 0.59 0.64)
			(layers "B.Cu" "B.Mask" "B.Paste")
			(roundrect_rratio 0.25)
			(net 28 "GND")
			(pintype "passive")
		)
		(pad "2" smd roundrect
			(at 0.48 0 270)
			(size 0.59 0.64)
			(layers "B.Cu" "B.Mask" "B.Paste")
			(roundrect_rratio 0.25)
			(net 66 "Net-(J6-LED_GRN-)")
			(pintype "passive")
		)
	)
	(footprint "antmicro-footprints:R_0402_1005Metric"
		(layer "B.Cu")
		(at 109.5 70.6 180)
		(descr "Resistor SMD 0402")
		(tags "resistor SMD 0402")
		(property "Reference" "R166"
			(at -1.44 5.61 0)
			(layer "B.SilkS")
			(effects
				(font
					(size 0.7 0.7)
					(thickness 0.15)
				)
				(justify left bottom mirror)
			)
		)
		(property "Value" "R_10k_0402"
			(at -1.011843 -1.772046 0)
			(layer "B.Fab")
			(hide yes)
			(effects
				(font
					(size 0.7 0.7)
					(thickness 0.15)
				)
				(justify left bottom mirror)
			)
		)
		(property "Datasheet" "https://www.bourns.com/docs/product-datasheets/cr.pdf"
			(at 0 0 0)
			(layer "B.Fab")
			(hide yes)
			(effects
				(font
					(size 1.27 1.27)
					(thickness 0.15)
				)
				(justify mirror)
			)
		)
		(property "Description" "SMD Chip Resistor, 10 kohm, ± 1%, 62.5 mW, 0402 [1005 Metric], Thick Film, General Purpose"
			(at 0 0 0)
			(layer "B.Fab")
			(hide yes)
			(effects
				(font
					(size 1.27 1.27)
					(thickness 0.15)
				)
				(justify mirror)
			)
		)
		(property "MPN" "CR0402-FX-1002GLF"
			(at 0 0 180)
			(unlocked yes)
			(layer "B.Fab")
			(hide yes)
			(effects
				(font
					(size 1 1)
					(thickness 0.15)
				)
				(justify mirror)
			)
		)
		(property "Manufacturer" "Bourns"
			(at 0 0 180)
			(unlocked yes)
			(layer "B.Fab")
			(hide yes)
			(effects
				(font
					(size 1 1)
					(thickness 0.15)
				)
				(justify mirror)
			)
		)
		(property "License" "Apache-2.0"
			(at 0 0 180)
			(unlocked yes)
			(layer "B.Fab")
			(hide yes)
			(effects
				(font
					(size 1 1)
					(thickness 0.15)
				)
				(justify mirror)
			)
		)
		(property "Author" "Antmicro"
			(at 0 0 180)
			(unlocked yes)
			(layer "B.Fab")
			(hide yes)
			(effects
				(font
					(size 1 1)
					(thickness 0.15)
				)
				(justify mirror)
			)
		)
		(property "Val" "10k"
			(at 0 0 180)
			(unlocked yes)
			(layer "B.Fab")
			(hide yes)
			(effects
				(font
					(size 1 1)
					(thickness 0.15)
				)
				(justify mirror)
			)
		)
		(property "Tolerance" "1%"
			(at 0 0 180)
			(unlocked yes)
			(layer "B.Fab")
			(hide yes)
			(effects
				(font
					(size 1 1)
					(thickness 0.15)
				)
				(justify mirror)
			)
		)
		(sheetname "/OCuLink/")
		(sheetfile "oculink.kicad_sch")
		(attr smd exclude_from_pos_files exclude_from_bom dnp)
		(fp_rect
			(start -0.925 0.47)
			(end 0.925 -0.47)
			(stroke
				(width 0.05)
				(type default)
			)
			(fill no)
			(layer "B.CrtYd")
		)
		(fp_rect
			(start -0.5 0.25)
			(end 0.5 -0.25)
			(stroke
				(width 0.15)
				(type solid)
			)
			(fill no)
			(layer "B.Fab")
		)
		(pad "1" smd roundrect
			(at -0.48 0 180)
			(size 0.59 0.64)
			(layers "B.Cu" "B.Mask" "B.Paste")
			(roundrect_rratio 0.25)
			(net 320 "/OCuLink/~{CWAKE}_R")
			(pintype "passive")
		)
		(pad "2" smd roundrect
			(at 0.48 0 180)
			(size 0.59 0.64)
			(layers "B.Cu" "B.Mask" "B.Paste")
			(roundrect_rratio 0.25)
			(net 7 "+3V3")
			(pintype "passive")
		)
	)
	(footprint "antmicro-footprints:R_0402_1005Metric"
		(layer "B.Cu")
		(at 96.45 98.1)
		(descr "Resistor SMD 0402")
		(tags "resistor SMD 0402")
		(property "Reference" "R63"
			(at 0.9 -0.35 0)
			(layer "B.SilkS")
			(effects
				(font
					(size 0.7 0.7)
					(thickness 0.15)
				)
				(justify right top mirror)
			)
		)
		(property "Value" "R_3k3_0402"
			(at -1.011843 -1.772046 0)
			(layer "B.Fab")
			(hide yes)
			(effects
				(font
					(size 0.7 0.7)
					(thickness 0.15)
				)
				(justify right top mirror)
			)
		)
		(property "Datasheet" "https://www.bourns.com/docs/product-datasheets/cr.pdf"
			(at 0 0 0)
			(layer "B.Fab")
			(hide yes)
			(effects
				(font
					(size 1.27 1.27)
					(thickness 0.15)
				)
				(justify mirror)
			)
		)
		(property "Description" "SMD Chip Resistor, 3.3 kohm, ± 1%, 63 mW, 0402 [1005 Metric], Thick Film, General Purpose"
			(at 0 0 0)
			(layer "B.Fab")
			(hide yes)
			(effects
				(font
					(size 1.27 1.27)
					(thickness 0.15)
				)
				(justify mirror)
			)
		)
		(property "MPN" "CR0402-FX-3301GLF"
			(at 0 0 0)
			(unlocked yes)
			(layer "B.Fab")
			(hide yes)
			(effects
				(font
					(size 1 1)
					(thickness 0.15)
				)
				(justify mirror)
			)
		)
		(property "Manufacturer" "Bourns"
			(at 0 0 0)
			(unlocked yes)
			(layer "B.Fab")
			(hide yes)
			(effects
				(font
					(size 1 1)
					(thickness 0.15)
				)
				(justify mirror)
			)
		)
		(property "License" "Apache-2.0"
			(at 0 0 0)
			(unlocked yes)
			(layer "B.Fab")
			(hide yes)
			(effects
				(font
					(size 1 1)
					(thickness 0.15)
				)
				(justify mirror)
			)
		)
		(property "Author" "Antmicro"
			(at 0 0 0)
			(unlocked yes)
			(layer "B.Fab")
			(hide yes)
			(effects
				(font
					(size 1 1)
					(thickness 0.15)
				)
				(justify mirror)
			)
		)
		(property "Val" "3k3"
			(at 0 0 0)
			(unlocked yes)
			(layer "B.Fab")
			(hide yes)
			(effects
				(font
					(size 1 1)
					(thickness 0.15)
				)
				(justify mirror)
			)
		)
		(property "Tolerance" "1%"
			(at 0 0 0)
			(unlocked yes)
			(layer "B.Fab")
			(hide yes)
			(effects
				(font
					(size 1 1)
					(thickness 0.15)
				)
				(justify mirror)
			)
		)
		(sheetname "/X710-AT2 10GbE/")
		(sheetfile "x710-at2-10gbe.kicad_sch")
		(attr smd)
		(fp_rect
			(start -0.925 0.47)
			(end 0.925 -0.47)
			(stroke
				(width 0.05)
				(type default)
			)
			(fill no)
			(layer "B.CrtYd")
		)
		(fp_rect
			(start -0.5 0.25)
			(end 0.5 -0.25)
			(stroke
				(width 0.15)
				(type solid)
			)
			(fill no)
			(layer "B.Fab")
		)
		(pad "1" smd roundrect
			(at -0.48 0)
			(size 0.59 0.64)
			(layers "B.Cu" "B.Mask" "B.Paste")
			(roundrect_rratio 0.25)
			(net 102 "/X710-AT2 10GbE/MDC1_SCL1")
			(pintype "passive")
		)
		(pad "2" smd roundrect
			(at 0.48 0)
			(size 0.59 0.64)
			(layers "B.Cu" "B.Mask" "B.Paste")
			(roundrect_rratio 0.25)
			(net 7 "+3V3")
			(pintype "passive")
		)
	)
)
